# T6G (Grand Teton) — schematic netlist excerpt (pin names and nets, part order shuffled) for the footprints in the layout excerpt that follows; sources: Cadence DE-HDL packaged netlist, KiCad conversion of 04192023_DAF0TMB3IC0_F0TG_MB_C_brd_V02_OCP.brd

R6722  Q_RES  4.7K 5% EMPTY  pkg 0201LF  page 320 : A = P1V8_CPU1_RT_1D ; B = RT_CPU1_P0_SCAN_MODE
R529  Q_RES  0 5% CHIP  pkg 0402LF  page 54 : A = JTAG_CPU1_R_TDO ; B = JTAG_CPU1_TDO
R4166  Q_RES  4.7K 5% CHIP  pkg 0402LF  page 124 : A = P3V3_AUX ; B = GPU_3V3IO_RSVD3_N

(kicad_pcb
	(version 20260206)
	(generator "pcbnew")
	(generator_version "10.0")
	(general
		(thickness 1.6)
		(legacy_teardrops no)
	)
	(paper "A4")
	(title_block
		(title "04192023_DAF0TMB3IC0_F0TG_MB_C_brd_V02_OCP.brd")
		(comment 1 "Grand Teton / footprints 6377-6379 of 8354")
	)
	(layers
		(0 "F.Cu" signal "TOP")
		(4 "In1.Cu" signal "GND")
		(6 "In2.Cu" signal "IN1")
		(8 "In3.Cu" signal "GND1")
		(10 "In4.Cu" signal "IN2")
		(12 "In5.Cu" signal "GND2")
		(14 "In6.Cu" signal "IN3")
		(16 "In7.Cu" signal "GND3")
		(18 "In8.Cu" signal "VCC")
		(20 "In9.Cu" signal "VCC1")
		(22 "In10.Cu" signal "GND4")
		(24 "In11.Cu" signal "IN4")
		(26 "In12.Cu" signal "GND5")
		(28 "In13.Cu" signal "IN5")
		(30 "In14.Cu" signal "GND6")
		(32 "In15.Cu" signal "IN6")
		(34 "In16.Cu" signal "GND7")
		(2 "B.Cu" signal "BOTTOM")
		(9 "F.Adhes" user "F.Adhesive")
		(11 "B.Adhes" user "B.Adhesive")
		(13 "F.Paste" user "Package Geometry/Pastemask Top")
		(15 "B.Paste" user "Package Geometry/Pastemask Bottom")
		(5 "F.SilkS" user "Ref Des/Silkscreen Top")
		(7 "B.SilkS" user "Ref Des/Silkscreen Bottom")
		(1 "F.Mask" user "Board Geometry/Soldermask Top")
		(3 "B.Mask" user "Board Geometry/Soldermask Bottom")
		(17 "Dwgs.User" user "User.Drawings")
		(19 "Cmts.User" user "User.Comments")
		(21 "Eco1.User" user "User.Eco1")
		(23 "Eco2.User" user "User.Eco2")
		(25 "Edge.Cuts" user "Board Geometry/Outline")
		(27 "Margin" user)
		(31 "F.CrtYd" user "Package Geometry/Place Bound Top")
		(29 "B.CrtYd" user "Package Geometry/Place Bound Bottom")
		(35 "F.Fab" user "Ref Des/Assembly Top")
		(33 "B.Fab" user "Ref Des/Assembly Bottom")
	)
	(footprint ""
		(layer "B.Cu")
		(at 434.39842 -438.1119 90)
		(property "Reference" "R4166"
			(at 0 0 90)
			(layer "B.SilkS")
			(hide yes)
			(effects
				(font
					(size 1.27 1.27)
				)
				(justify mirror)
			)
		)
		(property "Value" ""
			(at 0 0 90)
			(layer "B.Fab")
			(effects
				(font
					(size 1.27 1.27)
				)
				(justify mirror)
			)
		)
		(duplicate_pad_numbers_are_jumpers no)
		(fp_line
			(start 0.7874 -0.4064)
			(end -0.7874 -0.4064)
			(stroke
				(width 0.1524)
				(type default)
			)
			(layer "B.SilkS")
		)
		(fp_line
			(start -0.7874 -0.4064)
			(end -0.7874 0.4064)
			(stroke
				(width 0.1524)
				(type default)
			)
			(layer "B.SilkS")
		)
		(fp_line
			(start 0.7874 0.4064)
			(end 0.7874 -0.4064)
			(stroke
				(width 0.1524)
				(type default)
			)
			(layer "B.SilkS")
		)
		(fp_line
			(start -0.7874 0.4064)
			(end 0.7874 0.4064)
			(stroke
				(width 0.1524)
				(type default)
			)
			(layer "B.SilkS")
		)
		(fp_line
			(start 0.67945 -0.305054)
			(end 0.12065 -0.305054)
			(stroke
				(width 0.1)
				(type default)
			)
			(layer "B.Fab")
		)
		(fp_line
			(start 0.12065 -0.305054)
			(end 0.12065 -0.2794)
			(stroke
				(width 0.1)
				(type default)
			)
			(layer "B.Fab")
		)
		(fp_line
			(start -0.12065 -0.3048)
			(end -0.67945 -0.3048)
			(stroke
				(width 0.1)
				(type default)
			)
			(layer "B.Fab")
		)
		(fp_line
			(start -0.67945 -0.3048)
			(end -0.67945 0.3048)
			(stroke
				(width 0.1)
				(type default)
			)
			(layer "B.Fab")
		)
		(fp_line
			(start 0.12065 -0.2794)
			(end -0.12065 -0.2794)
			(stroke
				(width 0.1)
				(type default)
			)
			(layer "B.Fab")
		)
		(fp_line
			(start -0.12065 -0.2794)
			(end -0.12065 -0.3048)
			(stroke
				(width 0.1)
				(type default)
			)
			(layer "B.Fab")
		)
		(fp_line
			(start 0.12065 0.2794)
			(end 0.12065 0.3048)
			(stroke
				(width 0.1)
				(type default)
			)
			(layer "B.Fab")
		)
		(fp_line
			(start -0.120396 0.2794)
			(end 0.12065 0.2794)
			(stroke
				(width 0.1)
				(type default)
			)
			(layer "B.Fab")
		)
		(fp_line
			(start 0.67945 0.3048)
			(end 0.67945 -0.305054)
			(stroke
				(width 0.1)
				(type default)
			)
			(layer "B.Fab")
		)
		(fp_line
			(start 0.12065 0.3048)
			(end 0.67945 0.3048)
			(stroke
				(width 0.1)
				(type default)
			)
			(layer "B.Fab")
		)
		(fp_line
			(start -0.120396 0.3048)
			(end -0.120396 0.2794)
			(stroke
				(width 0.1)
				(type default)
			)
			(layer "B.Fab")
		)
		(fp_line
			(start -0.67945 0.3048)
			(end -0.120396 0.3048)
			(stroke
				(width 0.1)
				(type default)
			)
			(layer "B.Fab")
		)
		(pad "1" smd circle
			(at 0.40005 0 270)
			(size 0 0)
			(layers "B.Cu" "B.Mask" "B.Paste")
			(net "P3V3_AUX")
		)
		(pad "2" smd circle
			(at -0.40005 0 270)
			(size 0 0)
			(layers "B.Cu" "B.Mask" "B.Paste")
			(net "GPU_3V3IO_RSVD3_N")
		)
	)
	(footprint ""
		(layer "B.Cu")
		(at 131.59105 -213.203028 90)
		(property "Reference" "R529"
			(at 0 0 90)
			(layer "B.SilkS")
			(hide yes)
			(effects
				(font
					(size 1.27 1.27)
				)
				(justify mirror)
			)
		)
		(property "Value" ""
			(at 0 0 90)
			(layer "B.Fab")
			(effects
				(font
					(size 1.27 1.27)
				)
				(justify mirror)
			)
		)
		(duplicate_pad_numbers_are_jumpers no)
		(fp_line
			(start 0.7874 -0.4064)
			(end -0.7874 -0.4064)
			(stroke
				(width 0.1524)
				(type default)
			)
			(layer "B.SilkS")
		)
		(fp_line
			(start -0.7874 -0.4064)
			(end -0.7874 0.4064)
			(stroke
				(width 0.1524)
				(type default)
			)
			(layer "B.SilkS")
		)
		(fp_line
			(start 0.7874 0.4064)
			(end 0.7874 -0.4064)
			(stroke
				(width 0.1524)
				(type default)
			)
			(layer "B.SilkS")
		)
		(fp_line
			(start -0.7874 0.4064)
			(end 0.7874 0.4064)
			(stroke
				(width 0.1524)
				(type default)
			)
			(layer "B.SilkS")
		)
		(fp_line
			(start 0.67945 -0.305054)
			(end 0.12065 -0.305054)
			(stroke
				(width 0.1)
				(type default)
			)
			(layer "B.Fab")
		)
		(fp_line
			(start 0.12065 -0.305054)
			(end 0.12065 -0.2794)
			(stroke
				(width 0.1)
				(type default)
			)
			(layer "B.Fab")
		)
		(fp_line
			(start -0.12065 -0.3048)
			(end -0.67945 -0.3048)
			(stroke
				(width 0.1)
				(type default)
			)
			(layer "B.Fab")
		)
		(fp_line
			(start -0.67945 -0.3048)
			(end -0.67945 0.3048)
			(stroke
				(width 0.1)
				(type default)
			)
			(layer "B.Fab")
		)
		(fp_line
			(start 0.12065 -0.2794)
			(end -0.12065 -0.2794)
			(stroke
				(width 0.1)
				(type default)
			)
			(layer "B.Fab")
		)
		(fp_line
			(start -0.12065 -0.2794)
			(end -0.12065 -0.3048)
			(stroke
				(width 0.1)
				(type default)
			)
			(layer "B.Fab")
		)
		(fp_line
			(start 0.12065 0.2794)
			(end 0.12065 0.3048)
			(stroke
				(width 0.1)
				(type default)
			)
			(layer "B.Fab")
		)
		(fp_line
			(start -0.120396 0.2794)
			(end 0.12065 0.2794)
			(stroke
				(width 0.1)
				(type default)
			)
			(layer "B.Fab")
		)
		(fp_line
			(start 0.67945 0.3048)
			(end 0.67945 -0.305054)
			(stroke
				(width 0.1)
				(type default)
			)
			(layer "B.Fab")
		)
		(fp_line
			(start 0.12065 0.3048)
			(end 0.67945 0.3048)
			(stroke
				(width 0.1)
				(type default)
			)
			(layer "B.Fab")
		)
		(fp_line
			(start -0.120396 0.3048)
			(end -0.120396 0.2794)
			(stroke
				(width 0.1)
				(type default)
			)
			(layer "B.Fab")
		)
		(fp_line
			(start -0.67945 0.3048)
			(end -0.120396 0.3048)
			(stroke
				(width 0.1)
				(type default)
			)
			(layer "B.Fab")
		)
		(pad "1" smd circle
			(at 0.40005 0 270)
			(size 0 0)
			(layers "B.Cu" "B.Mask" "B.Paste")
			(net "JTAG_CPU1_R_TDO")
		)
		(pad "2" smd circle
			(at -0.40005 0 270)
			(size 0 0)
			(layers "B.Cu" "B.Mask" "B.Paste")
			(net "JTAG_CPU1_TDO")
		)
	)
	(footprint ""
		(layer "B.Cu")
		(at 43.265852 -382.68656 180)
		(property "Reference" "R6722"
			(at 0 0 0)
			(layer "B.SilkS")
			(hide yes)
			(effects
				(font
					(size 1.27 1.27)
				)
				(justify mirror)
			)
		)
		(property "Value" ""
			(at 0 0 0)
			(layer "B.Fab")
			(effects
				(font
					(size 1.27 1.27)
				)
				(justify mirror)
			)
		)
		(duplicate_pad_numbers_are_jumpers no)
		(fp_line
			(start 0.32512 0.175006)
			(end 0.32512 -0.175006)
			(stroke
				(width 0.1)
				(type default)
			)
			(layer "B.Fab")
		)
		(fp_line
			(start 0.32512 -0.175006)
			(end -0.32512 -0.175006)
			(stroke
				(width 0.1)
				(type default)
			)
			(layer "B.Fab")
		)
		(fp_line
			(start -0.32512 0.175006)
			(end 0.32512 0.175006)
			(stroke
				(width 0.1)
				(type default)
			)
			(layer "B.Fab")
		)
		(fp_line
			(start -0.32512 -0.175006)
			(end -0.32512 0.175006)
			(stroke
				(width 0.1)
				(type default)
			)
			(layer "B.Fab")
		)
		(pad "1" smd rect
			(at 0.2667 0)
			(size 0.3048 0.381)
			(layers "B.Cu" "B.Mask" "B.Paste")
			(net "P1V8_CPU1_RT_1D")
		)
		(pad "2" smd rect
			(at -0.2667 0 180)
			(size 0.3048 0.381)
			(layers "B.Cu" "B.Mask" "B.Paste")
			(net "RT_CPU1_P0_SCAN_MODE")
		)
	)
)
